# T6G (Grand Teton) — schematic netlist excerpt (pin names and nets, part order shuffled) for the footprints in the layout excerpt that follows; sources: Cadence DE-HDL packaged netlist, KiCad conversion of 04192023_DAF0TMB3IC0_F0TG_MB_C_brd_V02_OCP.brd

PC60  Q_CAP  22UF 16V 20% X6S  pkg C0805  page 226 : A = SW_P12V_AUX_PVDD18_S5_P1_FLT ; B = GND
C1338  Q_CAP  0.1UF 25V 10% X7R  pkg 0402  page 159 : A = P3V3_AUX ; B = GND
PC591  Q_CAP  2.2UF 16V 10% X6S  pkg C0603  page 190 : A = P3V3_AUX_VCC ; B = GND

(kicad_pcb
	(version 20260206)
	(generator "pcbnew")
	(generator_version "10.0")
	(general
		(thickness 1.6)
		(legacy_teardrops no)
	)
	(paper "A4")
	(title_block
		(title "04192023_DAF0TMB3IC0_F0TG_MB_C_brd_V02_OCP.brd")
		(comment 1 "Grand Teton / footprints 256-258 of 8354")
	)
	(layers
		(0 "F.Cu" signal "TOP")
		(4 "In1.Cu" signal "GND")
		(6 "In2.Cu" signal "IN1")
		(8 "In3.Cu" signal "GND1")
		(10 "In4.Cu" signal "IN2")
		(12 "In5.Cu" signal "GND2")
		(14 "In6.Cu" signal "IN3")
		(16 "In7.Cu" signal "GND3")
		(18 "In8.Cu" signal "VCC")
		(20 "In9.Cu" signal "VCC1")
		(22 "In10.Cu" signal "GND4")
		(24 "In11.Cu" signal "IN4")
		(26 "In12.Cu" signal "GND5")
		(28 "In13.Cu" signal "IN5")
		(30 "In14.Cu" signal "GND6")
		(32 "In15.Cu" signal "IN6")
		(34 "In16.Cu" signal "GND7")
		(2 "B.Cu" signal "BOTTOM")
		(9 "F.Adhes" user "F.Adhesive")
		(11 "B.Adhes" user "B.Adhesive")
		(13 "F.Paste" user "Package Geometry/Pastemask Top")
		(15 "B.Paste" user "Package Geometry/Pastemask Bottom")
		(5 "F.SilkS" user "Ref Des/Silkscreen Top")
		(7 "B.SilkS" user "Ref Des/Silkscreen Bottom")
		(1 "F.Mask" user "Board Geometry/Soldermask Top")
		(3 "B.Mask" user "Board Geometry/Soldermask Bottom")
		(17 "Dwgs.User" user "User.Drawings")
		(19 "Cmts.User" user "User.Comments")
		(21 "Eco1.User" user "User.Eco1")
		(23 "Eco2.User" user "User.Eco2")
		(25 "Edge.Cuts" user "Board Geometry/Outline")
		(27 "Margin" user)
		(31 "F.CrtYd" user "Package Geometry/Place Bound Top")
		(29 "B.CrtYd" user "Package Geometry/Place Bound Bottom")
		(35 "F.Fab" user "Ref Des/Assembly Top")
		(33 "B.Fab" user "Ref Des/Assembly Bottom")
	)
	(footprint ""
		(layer "F.Cu")
		(at 76.971906 -152.990804 90)
		(property "Reference" "PC60"
			(at 0 0 90)
			(layer "F.SilkS")
			(hide yes)
			(effects
				(font
					(size 1.27 1.27)
				)
			)
		)
		(property "Value" ""
			(at 0 0 90)
			(layer "F.Fab")
			(effects
				(font
					(size 1.27 1.27)
				)
			)
		)
		(duplicate_pad_numbers_are_jumpers no)
		(fp_line
			(start 1.524 -0.762)
			(end 1.524 0.762)
			(stroke
				(width 0.1524)
				(type default)
			)
			(layer "F.SilkS")
		)
		(fp_line
			(start -1.524 -0.762)
			(end 1.524 -0.762)
			(stroke
				(width 0.1524)
				(type default)
			)
			(layer "F.SilkS")
		)
		(fp_line
			(start 1.524 0.762)
			(end -1.524 0.762)
			(stroke
				(width 0.1524)
				(type default)
			)
			(layer "F.SilkS")
		)
		(fp_line
			(start -1.524 0.762)
			(end -1.524 -0.762)
			(stroke
				(width 0.1524)
				(type default)
			)
			(layer "F.SilkS")
		)
		(fp_line
			(start 1.1049 -0.724916)
			(end -1.1049 -0.724916)
			(stroke
				(width 0.1)
				(type default)
			)
			(layer "F.Fab")
		)
		(fp_line
			(start -1.1049 -0.724916)
			(end -1.1049 0.724916)
			(stroke
				(width 0.1)
				(type default)
			)
			(layer "F.Fab")
		)
		(fp_line
			(start 1.1049 0.724916)
			(end 1.1049 -0.724916)
			(stroke
				(width 0.1)
				(type default)
			)
			(layer "F.Fab")
		)
		(fp_line
			(start -1.1049 0.724916)
			(end 1.1049 0.724916)
			(stroke
				(width 0.1)
				(type default)
			)
			(layer "F.Fab")
		)
		(pad "1" smd rect
			(at -0.889 0 270)
			(size 1.016 1.27)
			(layers "F.Cu" "F.Mask" "F.Paste")
			(net "SW_P12V_AUX_PVDD18_S5_P1_FLT")
		)
		(pad "2" smd rect
			(at 0.889 0 270)
			(size 1.016 1.27)
			(layers "F.Cu" "F.Mask" "F.Paste")
			(net "GND")
		)
	)
	(footprint ""
		(layer "F.Cu")
		(at 461.689196 -49.453546 -90)
		(property "Reference" "PC591"
			(at 0 0 270)
			(layer "F.SilkS")
			(hide yes)
			(effects
				(font
					(size 1.27 1.27)
				)
			)
		)
		(property "Value" ""
			(at 0 0 270)
			(layer "F.Fab")
			(effects
				(font
					(size 1.27 1.27)
				)
			)
		)
		(duplicate_pad_numbers_are_jumpers no)
		(fp_line
			(start -1.2954 0.5842)
			(end -1.2954 -0.5842)
			(stroke
				(width 0.1524)
				(type default)
			)
			(layer "F.SilkS")
		)
		(fp_line
			(start 1.2954 0.5842)
			(end -1.2954 0.5842)
			(stroke
				(width 0.1524)
				(type default)
			)
			(layer "F.SilkS")
		)
		(fp_line
			(start -1.2954 -0.5842)
			(end 1.2954 -0.5842)
			(stroke
				(width 0.1524)
				(type default)
			)
			(layer "F.SilkS")
		)
		(fp_line
			(start 1.2954 -0.5842)
			(end 1.2954 0.5842)
			(stroke
				(width 0.1524)
				(type default)
			)
			(layer "F.SilkS")
		)
		(fp_line
			(start -0.8636 0.4572)
			(end -0.8636 0.4064)
			(stroke
				(width 0.1)
				(type default)
			)
			(layer "F.Fab")
		)
		(fp_line
			(start 0.8636 0.4572)
			(end -0.8636 0.4572)
			(stroke
				(width 0.1)
				(type default)
			)
			(layer "F.Fab")
		)
		(fp_line
			(start -1.1938 0.4064)
			(end -1.1938 -0.4064)
			(stroke
				(width 0.1)
				(type default)
			)
			(layer "F.Fab")
		)
		(fp_line
			(start -0.8636 0.4064)
			(end -1.1938 0.4064)
			(stroke
				(width 0.1)
				(type default)
			)
			(layer "F.Fab")
		)
		(fp_line
			(start 0.8636 0.4064)
			(end 0.8636 0.4572)
			(stroke
				(width 0.1)
				(type default)
			)
			(layer "F.Fab")
		)
		(fp_line
			(start 1.1938 0.4064)
			(end 0.8636 0.4064)
			(stroke
				(width 0.1)
				(type default)
			)
			(layer "F.Fab")
		)
		(fp_line
			(start -1.1938 -0.4064)
			(end -0.8636 -0.4064)
			(stroke
				(width 0.1)
				(type default)
			)
			(layer "F.Fab")
		)
		(fp_line
			(start -0.8636 -0.4064)
			(end -0.8636 -0.4572)
			(stroke
				(width 0.1)
				(type default)
			)
			(layer "F.Fab")
		)
		(fp_line
			(start 0.8636 -0.4064)
			(end 1.1938 -0.4064)
			(stroke
				(width 0.1)
				(type default)
			)
			(layer "F.Fab")
		)
		(fp_line
			(start 1.1938 -0.4064)
			(end 1.1938 0.4064)
			(stroke
				(width 0.1)
				(type default)
			)
			(layer "F.Fab")
		)
		(fp_line
			(start -0.8636 -0.4572)
			(end 0.8636 -0.4572)
			(stroke
				(width 0.1)
				(type default)
			)
			(layer "F.Fab")
		)
		(fp_line
			(start 0.8636 -0.4572)
			(end 0.8636 -0.4064)
			(stroke
				(width 0.1)
				(type default)
			)
			(layer "F.Fab")
		)
		(pad "1" smd rect
			(at -0.7366 0 180)
			(size 0.7112 0.8128)
			(layers "F.Cu" "F.Mask" "F.Paste")
			(net "P3V3_AUX_VCC")
		)
		(pad "2" smd rect
			(at 0.7366 0 180)
			(size 0.7112 0.8128)
			(layers "F.Cu" "F.Mask" "F.Paste")
			(net "GND")
		)
	)
	(footprint ""
		(layer "F.Cu")
		(at 38.416738 -169.763694 180)
		(property "Reference" "C1338"
			(at 0 0 180)
			(layer "F.SilkS")
			(hide yes)
			(effects
				(font
					(size 1.27 1.27)
				)
			)
		)
		(property "Value" ""
			(at 0 0 180)
			(layer "F.Fab")
			(effects
				(font
					(size 1.27 1.27)
				)
			)
		)
		(duplicate_pad_numbers_are_jumpers no)
		(fp_line
			(start 0.7874 0.4064)
			(end -0.7874 0.4064)
			(stroke
				(width 0.1524)
				(type default)
			)
			(layer "F.SilkS")
		)
		(fp_line
			(start 0.7874 -0.4064)
			(end 0.7874 0.4064)
			(stroke
				(width 0.1524)
				(type default)
			)
			(layer "F.SilkS")
		)
		(fp_line
			(start -0.7874 0.4064)
			(end -0.7874 -0.4064)
			(stroke
				(width 0.1524)
				(type default)
			)
			(layer "F.SilkS")
		)
		(fp_line
			(start -0.7874 -0.4064)
			(end 0.7874 -0.4064)
			(stroke
				(width 0.1524)
				(type default)
			)
			(layer "F.SilkS")
		)
		(fp_line
			(start 0.67945 0.3048)
			(end 0.120396 0.3048)
			(stroke
				(width 0.1)
				(type default)
			)
			(layer "F.Fab")
		)
		(fp_line
			(start 0.67945 -0.3048)
			(end 0.67945 0.3048)
			(stroke
				(width 0.1)
				(type default)
			)
			(layer "F.Fab")
		)
		(fp_line
			(start 0.12065 -0.2794)
			(end 0.12065 -0.3048)
			(stroke
				(width 0.1)
				(type default)
			)
			(layer "F.Fab")
		)
		(fp_line
			(start 0.12065 -0.3048)
			(end 0.67945 -0.3048)
			(stroke
				(width 0.1)
				(type default)
			)
			(layer "F.Fab")
		)
		(fp_line
			(start 0.120396 0.3048)
			(end 0.120396 0.2794)
			(stroke
				(width 0.1)
				(type default)
			)
			(layer "F.Fab")
		)
		(fp_line
			(start 0.120396 0.2794)
			(end -0.12065 0.2794)
			(stroke
				(width 0.1)
				(type default)
			)
			(layer "F.Fab")
		)
		(fp_line
			(start -0.12065 0.3048)
			(end -0.67945 0.3048)
			(stroke
				(width 0.1)
				(type default)
			)
			(layer "F.Fab")
		)
		(fp_line
			(start -0.12065 0.2794)
			(end -0.12065 0.3048)
			(stroke
				(width 0.1)
				(type default)
			)
			(layer "F.Fab")
		)
		(fp_line
			(start -0.12065 -0.2794)
			(end 0.12065 -0.2794)
			(stroke
				(width 0.1)
				(type default)
			)
			(layer "F.Fab")
		)
		(fp_line
			(start -0.12065 -0.305054)
			(end -0.12065 -0.2794)
			(stroke
				(width 0.1)
				(type default)
			)
			(layer "F.Fab")
		)
		(fp_line
			(start -0.67945 0.3048)
			(end -0.67945 -0.305054)
			(stroke
				(width 0.1)
				(type default)
			)
			(layer "F.Fab")
		)
		(fp_line
			(start -0.67945 -0.305054)
			(end -0.12065 -0.305054)
			(stroke
				(width 0.1)
				(type default)
			)
			(layer "F.Fab")
		)
		(pad "1" smd circle
			(at -0.40005 0 180)
			(size 0 0)
			(layers "F.Cu" "F.Mask" "F.Paste")
			(net "P3V3_AUX")
		)
		(pad "2" smd circle
			(at 0.40005 0 180)
			(size 0 0)
			(layers "F.Cu" "F.Mask" "F.Paste")
			(net "GND")
		)
	)
)
